(kicad_pcb
	(version 20260206)
	(generator "pcbnew")
	(generator_version "10.0")
	(general
		(thickness 1.6)
		(legacy_teardrops no)
	)
	(paper "A4")
	(title_block
		(title "panther-plus-userver — 13130-1b_20150205.brd")
		(comment 1 "Honey Badger (Wiwynn) / footprint 1214 of 1509 (DIMM3), pads 65-71 of 210")
	)
	(layers
		(0 "F.Cu" signal "TOP")
		(4 "In1.Cu" signal "L2")
		(6 "In2.Cu" signal "L3")
		(8 "In3.Cu" signal "L4")
		(10 "In4.Cu" signal "L5")
		(12 "In5.Cu" signal "L6")
		(14 "In6.Cu" signal "L7")
		(16 "In7.Cu" signal "L8")
		(18 "In8.Cu" signal "L9")
		(20 "In9.Cu" signal "L10")
		(22 "In10.Cu" signal "L11")
		(2 "B.Cu" signal "BOTTOM")
		(9 "F.Adhes" user "F.Adhesive")
		(11 "B.Adhes" user "B.Adhesive")
		(13 "F.Paste" user "Package Geometry/Pastemask Top")
		(15 "B.Paste" user "Package Geometry/Pastemask Bottom")
		(5 "F.SilkS" user "Ref Des/Silkscreen Top")
		(7 "B.SilkS" user "Ref Des/Silkscreen Bottom")
		(1 "F.Mask" user "Board Geometry/Soldermask Top")
		(3 "B.Mask" user "Board Geometry/Soldermask Bottom")
		(17 "Dwgs.User" user "User.Drawings")
		(19 "Cmts.User" user "User.Comments")
		(21 "Eco1.User" user "User.Eco1")
		(23 "Eco2.User" user "User.Eco2")
		(25 "Edge.Cuts" user "Board Geometry/Outline")
		(27 "Margin" user)
		(31 "F.CrtYd" user "Package Geometry/Place Bound Top")
		(29 "B.CrtYd" user "Package Geometry/Place Bound Bottom")
		(35 "F.Fab" user "Ref Des/Assembly Top")
		(33 "B.Fab" user "Ref Des/Assembly Bottom")
	)
	(footprint ""
		(layer "B.Cu")
		(at 159.999934 -5.790692)
		(property "Reference" "DIMM3"
			(at 0 0 0)
			(layer "B.SilkS")
			(hide yes)
			(effects
				(font
					(size 1.27 1.27)
				)
				(justify mirror)
			)
		)
		(property "Value" "DDR3-204P-142-COLAY-1-GP-U"
			(at 41.312338 -16.676878 0)
			(unlocked yes)
			(layer "B.Fab")
			(hide yes)
			(effects
				(font
					(size 1.016 1.016)
					(thickness 0.1524)
				)
				(justify mirror)
			)
		)
		(property "Device Type" "AS0A626-J8R6-7H-COLAY-1"
			(at 41.312338 -18.200878 0)
			(unlocked yes)
			(layer "B.Fab")
			(hide yes)
			(effects
				(font
					(size 1.016 1.016)
					(thickness 0.1524)
				)
				(justify mirror)
			)
		)
		(duplicate_pad_numbers_are_jumpers no)
		(pad "63" smd custom
			(at -13.050012 -4.100068 180)
			(size 0.1143 0.1143)
			(layers "B.Cu" "B.Mask" "B.Paste")
			(net "M_B_DQ26")
			(options
				(clearance outline)
				(anchor circle)
			)
			(primitives
				(gr_poly
					(pts
						(xy 0 -0.9017) (xy -0.03175 -0.89916) (xy -0.0635 -0.889) (xy -0.09144 -0.87376) (xy -0.11684 -0.85344)
						(xy -0.13716 -0.82804) (xy -0.1524 -0.8001) (xy -0.16256 -0.76835) (xy -0.1651 -0.7366) (xy -0.1651 -0.19685)
						(xy -0.17272 -0.18923) (xy -0.17907 -0.18034) (xy -0.18669 -0.17145) (xy -0.19177 -0.16256) (xy -0.19812 -0.15367)
						(xy -0.20828 -0.13335) (xy -0.21971 -0.10287) (xy -0.22225 -0.09271) (xy -0.22479 -0.08128) (xy -0.22606 -0.07112)
						(xy -0.2286 -0.05969) (xy -0.2286 -0.01651) (xy -0.22606 -0.00508) (xy -0.22479 0.00508) (xy -0.22225 0.01651)
						(xy -0.21971 0.02667) (xy -0.20828 0.05715) (xy -0.19812 0.07747) (xy -0.19177 0.08636) (xy -0.18669 0.09525)
						(xy -0.17907 0.10414) (xy -0.17272 0.11303) (xy -0.1651 0.12065) (xy -0.1651 0.7366) (xy -0.16256 0.76835)
						(xy -0.1524 0.8001) (xy -0.13716 0.82804) (xy -0.11684 0.85344) (xy -0.09144 0.87376) (xy -0.0635 0.889)
						(xy -0.03175 0.89916) (xy 0 0.9017) (xy 0.03175 0.89916) (xy 0.0635 0.889) (xy 0.09144 0.87376)
						(xy 0.11684 0.85344) (xy 0.13716 0.82804) (xy 0.1524 0.8001) (xy 0.16256 0.76835) (xy 0.1651 0.7366)
						(xy 0.1651 0.11938) (xy 0.17272 0.11176) (xy 0.19812 0.0762) (xy 0.2032 0.06604) (xy 0.20701 0.05715)
						(xy 0.21209 0.04699) (xy 0.2159 0.03683) (xy 0.21844 0.02667) (xy 0.22225 0.01524) (xy 0.22352 0.00508)
						(xy 0.22606 -0.00508) (xy 0.22733 -0.01651) (xy 0.22733 -0.02667) (xy 0.2286 -0.0381) (xy 0.22733 -0.04953)
						(xy 0.22733 -0.05969) (xy 0.22606 -0.07112) (xy 0.22352 -0.08128) (xy 0.22225 -0.09144) (xy 0.21844 -0.10287)
						(xy 0.2159 -0.11303) (xy 0.21209 -0.12319) (xy 0.20701 -0.13335) (xy 0.2032 -0.14224) (xy 0.19812 -0.1524)
						(xy 0.17272 -0.18796) (xy 0.1651 -0.19558) (xy 0.1651 -0.7366) (xy 0.16256 -0.76835) (xy 0.1524 -0.8001)
						(xy 0.13716 -0.82804) (xy 0.11684 -0.85344) (xy 0.09144 -0.87376) (xy 0.0635 -0.889) (xy 0.03175 -0.89916)
					)
					(width 0)
					(fill yes)
				)
			)
		)
		(pad "64" smd custom
			(at -12.750038 4.100068 180)
			(size 0.1143 0.1143)
			(layers "B.Cu" "B.Mask" "B.Paste")
			(net "GND")
			(options
				(clearance outline)
				(anchor circle)
			)
			(primitives
				(gr_poly
					(pts
						(xy 0 -0.9017) (xy -0.03175 -0.89916) (xy -0.0635 -0.889) (xy -0.09144 -0.87376) (xy -0.11684 -0.85344)
						(xy -0.13716 -0.82804) (xy -0.1524 -0.8001) (xy -0.16256 -0.76835) (xy -0.1651 -0.7366) (xy -0.1651 -0.11938)
						(xy -0.17272 -0.11176) (xy -0.19812 -0.0762) (xy -0.2032 -0.06604) (xy -0.20701 -0.05715) (xy -0.21209 -0.04699)
						(xy -0.2159 -0.03683) (xy -0.21844 -0.02667) (xy -0.22225 -0.01524) (xy -0.22352 -0.00508) (xy -0.22606 0.00508)
						(xy -0.22733 0.01651) (xy -0.22733 0.02667) (xy -0.2286 0.0381) (xy -0.22733 0.04953) (xy -0.22733 0.05969)
						(xy -0.22606 0.07112) (xy -0.22352 0.08128) (xy -0.22225 0.09144) (xy -0.21844 0.10287) (xy -0.2159 0.11303)
						(xy -0.21209 0.12319) (xy -0.20701 0.13335) (xy -0.2032 0.14224) (xy -0.19812 0.1524) (xy -0.17272 0.18796)
						(xy -0.1651 0.19558) (xy -0.1651 0.7366) (xy -0.16256 0.76835) (xy -0.1524 0.8001) (xy -0.13716 0.82804)
						(xy -0.11684 0.85344) (xy -0.09144 0.87376) (xy -0.0635 0.889) (xy -0.03175 0.89916) (xy 0 0.9017)
						(xy 0.03175 0.89916) (xy 0.0635 0.889) (xy 0.09144 0.87376) (xy 0.11684 0.85344) (xy 0.13716 0.82804)
						(xy 0.1524 0.8001) (xy 0.16256 0.76835) (xy 0.1651 0.7366) (xy 0.1651 0.19685) (xy 0.17272 0.18923)
						(xy 0.17907 0.18034) (xy 0.18669 0.17145) (xy 0.19177 0.16256) (xy 0.19812 0.15367) (xy 0.20828 0.13335)
						(xy 0.21971 0.10287) (xy 0.22225 0.09271) (xy 0.22479 0.08128) (xy 0.22606 0.07112) (xy 0.2286 0.05969)
						(xy 0.2286 0.01651) (xy 0.22606 0.00508) (xy 0.22479 -0.00508) (xy 0.22225 -0.01651) (xy 0.21971 -0.02667)
						(xy 0.20828 -0.05715) (xy 0.19812 -0.07747) (xy 0.19177 -0.08636) (xy 0.18669 -0.09525) (xy 0.17907 -0.10414)
						(xy 0.17272 -0.11303) (xy 0.1651 -0.12065) (xy 0.1651 -0.7366) (xy 0.16256 -0.76835) (xy 0.1524 -0.8001)
						(xy 0.13716 -0.82804) (xy 0.11684 -0.85344) (xy 0.09144 -0.87376) (xy 0.0635 -0.889) (xy 0.03175 -0.89916)
					)
					(width 0)
					(fill yes)
				)
			)
		)
		(pad "65" smd custom
			(at -12.450064 -4.100068 180)
			(size 0.1143 0.1143)
			(layers "B.Cu" "B.Mask" "B.Paste")
			(net "M_B_DQ27")
			(options
				(clearance outline)
				(anchor circle)
			)
			(primitives
				(gr_poly
					(pts
						(xy 0 -0.9017) (xy -0.03175 -0.89916) (xy -0.0635 -0.889) (xy -0.09144 -0.87376) (xy -0.11684 -0.85344)
						(xy -0.13716 -0.82804) (xy -0.1524 -0.8001) (xy -0.16256 -0.76835) (xy -0.1651 -0.7366) (xy -0.1651 -0.44958)
						(xy -0.17272 -0.44196) (xy -0.19812 -0.4064) (xy -0.2032 -0.39624) (xy -0.20701 -0.38735) (xy -0.21209 -0.37719)
						(xy -0.2159 -0.36703) (xy -0.21844 -0.35687) (xy -0.22225 -0.34544) (xy -0.22352 -0.33528) (xy -0.22606 -0.32512)
						(xy -0.22733 -0.31369) (xy -0.22733 -0.30353) (xy -0.2286 -0.2921) (xy -0.22733 -0.28067) (xy -0.22733 -0.27051)
						(xy -0.22606 -0.25908) (xy -0.22352 -0.24892) (xy -0.22225 -0.23876) (xy -0.21844 -0.22733) (xy -0.2159 -0.21717)
						(xy -0.21209 -0.20701) (xy -0.20701 -0.19685) (xy -0.2032 -0.18796) (xy -0.19812 -0.1778) (xy -0.17272 -0.14224)
						(xy -0.1651 -0.13462) (xy -0.1651 0.7366) (xy -0.16256 0.76835) (xy -0.1524 0.8001) (xy -0.13716 0.82804)
						(xy -0.11684 0.85344) (xy -0.09144 0.87376) (xy -0.0635 0.889) (xy -0.03175 0.89916) (xy 0 0.9017)
						(xy 0.03175 0.89916) (xy 0.0635 0.889) (xy 0.09144 0.87376) (xy 0.11684 0.85344) (xy 0.13716 0.82804)
						(xy 0.1524 0.8001) (xy 0.16256 0.76835) (xy 0.1651 0.7366) (xy 0.1651 -0.13462) (xy 0.17272 -0.14224)
						(xy 0.19812 -0.1778) (xy 0.2032 -0.18796) (xy 0.20701 -0.19685) (xy 0.21209 -0.20701) (xy 0.2159 -0.21717)
						(xy 0.21844 -0.22733) (xy 0.22225 -0.23876) (xy 0.22352 -0.24892) (xy 0.22606 -0.25908) (xy 0.22733 -0.27051)
						(xy 0.22733 -0.28067) (xy 0.2286 -0.2921) (xy 0.22733 -0.30353) (xy 0.22733 -0.31369) (xy 0.22606 -0.32512)
						(xy 0.22352 -0.33528) (xy 0.22225 -0.34544) (xy 0.21844 -0.35687) (xy 0.2159 -0.36703) (xy 0.21209 -0.37719)
						(xy 0.20701 -0.38735) (xy 0.2032 -0.39624) (xy 0.19812 -0.4064) (xy 0.17272 -0.44196) (xy 0.1651 -0.44958)
						(xy 0.1651 -0.7366) (xy 0.16256 -0.76835) (xy 0.1524 -0.8001) (xy 0.13716 -0.82804) (xy 0.11684 -0.85344)
						(xy 0.09144 -0.87376) (xy 0.0635 -0.889) (xy 0.03175 -0.89916)
					)
					(width 0)
					(fill yes)
				)
			)
		)
		(pad "66" smd custom
			(at -12.15009 4.100068 180)
			(size 0.1143 0.1143)
			(layers "B.Cu" "B.Mask" "B.Paste")
			(net "M_B_DQ30")
			(options
				(clearance outline)
				(anchor circle)
			)
			(primitives
				(gr_poly
					(pts
						(xy 0 -0.9017) (xy -0.03175 -0.89916) (xy -0.0635 -0.889) (xy -0.09144 -0.87376) (xy -0.11684 -0.85344)
						(xy -0.13716 -0.82804) (xy -0.1524 -0.8001) (xy -0.16256 -0.76835) (xy -0.1651 -0.7366) (xy -0.1651 0.13462)
						(xy -0.17272 0.14224) (xy -0.19812 0.1778) (xy -0.2032 0.18796) (xy -0.20701 0.19685) (xy -0.21209 0.20701)
						(xy -0.2159 0.21717) (xy -0.21844 0.22733) (xy -0.22225 0.23876) (xy -0.22352 0.24892) (xy -0.22606 0.25908)
						(xy -0.22733 0.27051) (xy -0.22733 0.28067) (xy -0.2286 0.2921) (xy -0.22733 0.30353) (xy -0.22733 0.31369)
						(xy -0.22606 0.32512) (xy -0.22352 0.33528) (xy -0.22225 0.34544) (xy -0.21844 0.35687) (xy -0.2159 0.36703)
						(xy -0.21209 0.37719) (xy -0.20701 0.38735) (xy -0.2032 0.39624) (xy -0.19812 0.4064) (xy -0.17272 0.44196)
						(xy -0.1651 0.44958) (xy -0.1651 0.7366) (xy -0.16256 0.76835) (xy -0.1524 0.8001) (xy -0.13716 0.82804)
						(xy -0.11684 0.85344) (xy -0.09144 0.87376) (xy -0.0635 0.889) (xy -0.03175 0.89916) (xy 0 0.9017)
						(xy 0.03175 0.89916) (xy 0.0635 0.889) (xy 0.09144 0.87376) (xy 0.11684 0.85344) (xy 0.13716 0.82804)
						(xy 0.1524 0.8001) (xy 0.16256 0.76835) (xy 0.1651 0.7366) (xy 0.1651 0.44958) (xy 0.17272 0.44196)
						(xy 0.19812 0.4064) (xy 0.2032 0.39624) (xy 0.20701 0.38735) (xy 0.21209 0.37719) (xy 0.2159 0.36703)
						(xy 0.21844 0.35687) (xy 0.22225 0.34544) (xy 0.22352 0.33528) (xy 0.22606 0.32512) (xy 0.22733 0.31369)
						(xy 0.22733 0.30353) (xy 0.2286 0.2921) (xy 0.22733 0.28067) (xy 0.22733 0.27051) (xy 0.22606 0.25908)
						(xy 0.22352 0.24892) (xy 0.22225 0.23876) (xy 0.21844 0.22733) (xy 0.2159 0.21717) (xy 0.21209 0.20701)
						(xy 0.20701 0.19685) (xy 0.2032 0.18796) (xy 0.19812 0.1778) (xy 0.17272 0.14224) (xy 0.1651 0.13462)
						(xy 0.1651 -0.7366) (xy 0.16256 -0.76835) (xy 0.1524 -0.8001) (xy 0.13716 -0.82804) (xy 0.11684 -0.85344)
						(xy 0.09144 -0.87376) (xy 0.0635 -0.889) (xy 0.03175 -0.89916)
					)
					(width 0)
					(fill yes)
				)
			)
		)
		(pad "67" smd custom
			(at -11.850116 -4.100068 180)
			(size 0.1143 0.1143)
			(layers "B.Cu" "B.Mask" "B.Paste")
			(net "GND")
			(options
				(clearance outline)
				(anchor circle)
			)
			(primitives
				(gr_poly
					(pts
						(xy 0 -0.9017) (xy -0.03175 -0.89916) (xy -0.0635 -0.889) (xy -0.09144 -0.87376) (xy -0.11684 -0.85344)
						(xy -0.13716 -0.82804) (xy -0.1524 -0.8001) (xy -0.16256 -0.76835) (xy -0.1651 -0.7366) (xy -0.1651 -0.19685)
						(xy -0.17272 -0.18923) (xy -0.17907 -0.18034) (xy -0.18669 -0.17145) (xy -0.19177 -0.16256) (xy -0.19812 -0.15367)
						(xy -0.20828 -0.13335) (xy -0.21971 -0.10287) (xy -0.22225 -0.09271) (xy -0.22479 -0.08128) (xy -0.22606 -0.07112)
						(xy -0.2286 -0.05969) (xy -0.2286 -0.01651) (xy -0.22606 -0.00508) (xy -0.22479 0.00508) (xy -0.22225 0.01651)
						(xy -0.21971 0.02667) (xy -0.20828 0.05715) (xy -0.19812 0.07747) (xy -0.19177 0.08636) (xy -0.18669 0.09525)
						(xy -0.17907 0.10414) (xy -0.17272 0.11303) (xy -0.1651 0.12065) (xy -0.1651 0.7366) (xy -0.16256 0.76835)
						(xy -0.1524 0.8001) (xy -0.13716 0.82804) (xy -0.11684 0.85344) (xy -0.09144 0.87376) (xy -0.0635 0.889)
						(xy -0.03175 0.89916) (xy 0 0.9017) (xy 0.03175 0.89916) (xy 0.0635 0.889) (xy 0.09144 0.87376)
						(xy 0.11684 0.85344) (xy 0.13716 0.82804) (xy 0.1524 0.8001) (xy 0.16256 0.76835) (xy 0.1651 0.7366)
						(xy 0.1651 0.11938) (xy 0.17272 0.11176) (xy 0.19812 0.0762) (xy 0.2032 0.06604) (xy 0.20701 0.05715)
						(xy 0.21209 0.04699) (xy 0.2159 0.03683) (xy 0.21844 0.02667) (xy 0.22225 0.01524) (xy 0.22352 0.00508)
						(xy 0.22606 -0.00508) (xy 0.22733 -0.01651) (xy 0.22733 -0.02667) (xy 0.2286 -0.0381) (xy 0.22733 -0.04953)
						(xy 0.22733 -0.05969) (xy 0.22606 -0.07112) (xy 0.22352 -0.08128) (xy 0.22225 -0.09144) (xy 0.21844 -0.10287)
						(xy 0.2159 -0.11303) (xy 0.21209 -0.12319) (xy 0.20701 -0.13335) (xy 0.2032 -0.14224) (xy 0.19812 -0.1524)
						(xy 0.17272 -0.18796) (xy 0.1651 -0.19558) (xy 0.1651 -0.7366) (xy 0.16256 -0.76835) (xy 0.1524 -0.8001)
						(xy 0.13716 -0.82804) (xy 0.11684 -0.85344) (xy 0.09144 -0.87376) (xy 0.0635 -0.889) (xy 0.03175 -0.89916)
					)
					(width 0)
					(fill yes)
				)
			)
		)
		(pad "68" smd custom
			(at -11.549888 4.100068 180)
			(size 0.1143 0.1143)
			(layers "B.Cu" "B.Mask" "B.Paste")
			(net "M_B_DQ31")
			(options
				(clearance outline)
				(anchor circle)
			)
			(primitives
				(gr_poly
					(pts
						(xy 0 -0.9017) (xy -0.03175 -0.89916) (xy -0.0635 -0.889) (xy -0.09144 -0.87376) (xy -0.11684 -0.85344)
						(xy -0.13716 -0.82804) (xy -0.1524 -0.8001) (xy -0.16256 -0.76835) (xy -0.1651 -0.7366) (xy -0.1651 -0.11938)
						(xy -0.17272 -0.11176) (xy -0.19812 -0.0762) (xy -0.2032 -0.06604) (xy -0.20701 -0.05715) (xy -0.21209 -0.04699)
						(xy -0.2159 -0.03683) (xy -0.21844 -0.02667) (xy -0.22225 -0.01524) (xy -0.22352 -0.00508) (xy -0.22606 0.00508)
						(xy -0.22733 0.01651) (xy -0.22733 0.02667) (xy -0.2286 0.0381) (xy -0.22733 0.04953) (xy -0.22733 0.05969)
						(xy -0.22606 0.07112) (xy -0.22352 0.08128) (xy -0.22225 0.09144) (xy -0.21844 0.10287) (xy -0.2159 0.11303)
						(xy -0.21209 0.12319) (xy -0.20701 0.13335) (xy -0.2032 0.14224) (xy -0.19812 0.1524) (xy -0.17272 0.18796)
						(xy -0.1651 0.19558) (xy -0.1651 0.7366) (xy -0.16256 0.76835) (xy -0.1524 0.8001) (xy -0.13716 0.82804)
						(xy -0.11684 0.85344) (xy -0.09144 0.87376) (xy -0.0635 0.889) (xy -0.03175 0.89916) (xy 0 0.9017)
						(xy 0.03175 0.89916) (xy 0.0635 0.889) (xy 0.09144 0.87376) (xy 0.11684 0.85344) (xy 0.13716 0.82804)
						(xy 0.1524 0.8001) (xy 0.16256 0.76835) (xy 0.1651 0.7366) (xy 0.1651 0.19685) (xy 0.17272 0.18923)
						(xy 0.17907 0.18034) (xy 0.18669 0.17145) (xy 0.19177 0.16256) (xy 0.19812 0.15367) (xy 0.20828 0.13335)
						(xy 0.21971 0.10287) (xy 0.22225 0.09271) (xy 0.22479 0.08128) (xy 0.22606 0.07112) (xy 0.2286 0.05969)
						(xy 0.2286 0.01651) (xy 0.22606 0.00508) (xy 0.22479 -0.00508) (xy 0.22225 -0.01651) (xy 0.21971 -0.02667)
						(xy 0.20828 -0.05715) (xy 0.19812 -0.07747) (xy 0.19177 -0.08636) (xy 0.18669 -0.09525) (xy 0.17907 -0.10414)
						(xy 0.17272 -0.11303) (xy 0.1651 -0.12065) (xy 0.1651 -0.7366) (xy 0.16256 -0.76835) (xy 0.1524 -0.8001)
						(xy 0.13716 -0.82804) (xy 0.11684 -0.85344) (xy 0.09144 -0.87376) (xy 0.0635 -0.889) (xy 0.03175 -0.89916)
					)
					(width 0)
					(fill yes)
				)
			)
		)
		(pad "69" smd custom
			(at -11.249914 -4.100068 180)
			(size 0.1143 0.1143)
			(layers "B.Cu" "B.Mask" "B.Paste")
			(net "M_B_ECC0")
			(options
				(clearance outline)
				(anchor circle)
			)
			(primitives
				(gr_poly
					(pts
						(xy 0 -0.9017) (xy -0.03175 -0.89916) (xy -0.0635 -0.889) (xy -0.09144 -0.87376) (xy -0.11684 -0.85344)
						(xy -0.13716 -0.82804) (xy -0.1524 -0.8001) (xy -0.16256 -0.76835) (xy -0.1651 -0.7366) (xy -0.1651 -0.44958)
						(xy -0.17272 -0.44196) (xy -0.19812 -0.4064) (xy -0.2032 -0.39624) (xy -0.20701 -0.38735) (xy -0.21209 -0.37719)
						(xy -0.2159 -0.36703) (xy -0.21844 -0.35687) (xy -0.22225 -0.34544) (xy -0.22352 -0.33528) (xy -0.22606 -0.32512)
						(xy -0.22733 -0.31369) (xy -0.22733 -0.30353) (xy -0.2286 -0.2921) (xy -0.22733 -0.28067) (xy -0.22733 -0.27051)
						(xy -0.22606 -0.25908) (xy -0.22352 -0.24892) (xy -0.22225 -0.23876) (xy -0.21844 -0.22733) (xy -0.2159 -0.21717)
						(xy -0.21209 -0.20701) (xy -0.20701 -0.19685) (xy -0.2032 -0.18796) (xy -0.19812 -0.1778) (xy -0.17272 -0.14224)
						(xy -0.1651 -0.13462) (xy -0.1651 0.7366) (xy -0.16256 0.76835) (xy -0.1524 0.8001) (xy -0.13716 0.82804)
						(xy -0.11684 0.85344) (xy -0.09144 0.87376) (xy -0.0635 0.889) (xy -0.03175 0.89916) (xy 0 0.9017)
						(xy 0.03175 0.89916) (xy 0.0635 0.889) (xy 0.09144 0.87376) (xy 0.11684 0.85344) (xy 0.13716 0.82804)
						(xy 0.1524 0.8001) (xy 0.16256 0.76835) (xy 0.1651 0.7366) (xy 0.1651 -0.13462) (xy 0.17272 -0.14224)
						(xy 0.19812 -0.1778) (xy 0.2032 -0.18796) (xy 0.20701 -0.19685) (xy 0.21209 -0.20701) (xy 0.2159 -0.21717)
						(xy 0.21844 -0.22733) (xy 0.22225 -0.23876) (xy 0.22352 -0.24892) (xy 0.22606 -0.25908) (xy 0.22733 -0.27051)
						(xy 0.22733 -0.28067) (xy 0.2286 -0.2921) (xy 0.22733 -0.30353) (xy 0.22733 -0.31369) (xy 0.22606 -0.32512)
						(xy 0.22352 -0.33528) (xy 0.22225 -0.34544) (xy 0.21844 -0.35687) (xy 0.2159 -0.36703) (xy 0.21209 -0.37719)
						(xy 0.20701 -0.38735) (xy 0.2032 -0.39624) (xy 0.19812 -0.4064) (xy 0.17272 -0.44196) (xy 0.1651 -0.44958)
						(xy 0.1651 -0.7366) (xy 0.16256 -0.76835) (xy 0.1524 -0.8001) (xy 0.13716 -0.82804) (xy 0.11684 -0.85344)
						(xy 0.09144 -0.87376) (xy 0.0635 -0.889) (xy 0.03175 -0.89916)
					)
					(width 0)
					(fill yes)
				)
			)
		)
	)
)
